# T6G (Grand Teton) — schematic netlist excerpt (pin names and nets, part order shuffled) for the footprints in the layout excerpt that follows; sources: Cadence DE-HDL packaged netlist, KiCad conversion of 04192023_DAF0TMB3IC0_F0TG_MB_C_brd_V02_OCP.brd

J33  SCONN288_DDR506112002KQ  IO  pkg DDR288S_1-1VXC  page 103
  VIN_BULK0  = P12V_MEM_CPU1
  RFU0  = NC
  VIN_MGMT  = P3V3_AUX
  HSCL  = I3C_SPD_DDRF_CPU1_SCL
  HSDA  = I3C_SPD_DDRF_CPU1_SDA
  VSS0  = GND
  DQ0_A  = M_F_CPU1_SA_DQ<0>
  VSS1  = GND
  DQ1_A  = M_F_CPU1_SA_DQ<1>
  VSS2  = GND
  DQS0_A_T  = M_F_CPU1_SA_DQS_DP<0>
  DQS0_A_C  = M_F_CPU1_SA_DQS_DN<0>
  VSS3  = GND
  DQ4_A  = M_F_CPU1_SA_DQ<4>
  VSS4  = GND
  DQ5_A  = M_F_CPU1_SA_DQ<5>
  VSS5  = GND
  DQ8_A  = M_F_CPU1_SA_DQ<8>
  VSS6  = GND
  DQ9_A  = M_F_CPU1_SA_DQ<9>
  VSS7  = GND
  DQS1_A_T  = M_F_CPU1_SA_DQS_DP<1>
  DQS1_A_C  = M_F_CPU1_SA_DQS_DN<1>
  VSS8  = GND
  DQ12_A  = M_F_CPU1_SA_DQ<12>
  VSS9  = GND
  DQ13_A  = M_F_CPU1_SA_DQ<13>
  VSS10  = GND
  DQ16_A  = M_F_CPU1_SA_DQ<16>
  VSS11  = GND
  DQ17_A  = M_F_CPU1_SA_DQ<17>
  VSS12  = GND
  DQS2_A_T  = M_F_CPU1_SA_DQS_DP<2>
  DQS2_A_C  = M_F_CPU1_SA_DQS_DN<2>
  VSS13  = GND
  DQ20_A  = M_F_CPU1_SA_DQ<20>
  VSS14  = GND
  DQ21_A  = M_F_CPU1_SA_DQ<21>
  VSS15  = GND
  DQ24_A  = M_F_CPU1_SA_DQ<24>
  VSS16  = GND
  DQ25_A  = M_F_CPU1_SA_DQ<25>
  VSS17  = GND
  DQS3_A_T  = M_F_CPU1_SA_DQS_DP<3>
  DQS3_A_C  = M_F_CPU1_SA_DQS_DN<3>
  VSS18  = GND
  DQ28_A  = M_F_CPU1_SA_DQ<28>
  VSS19  = GND
  DQ29_A  = M_F_CPU1_SA_DQ<29>
  VSS20  = GND
  CB0_A  = M_F_CPU1_SA_CB<0>
  VSS21  = GND
  CB1_A  = M_F_CPU1_SA_CB<1>
  VSS22  = GND
  DQS4_A_T  = M_F_CPU1_SA_DQS_DP<4>
  DQS4_A_C  = M_F_CPU1_SA_DQS_DN<4>
  VSS23  = GND
  CB4_A  = M_F_CPU1_SA_CB<4>
  VSS24  = GND
  CB5_A  = M_F_CPU1_SA_CB<5>
  VSS25  = GND
  ALERT_N  = M_F_CPU1_ALERT_N
  VSS26  = GND
  CS0_A_N  = M_F_CPU1_SA_CS_N<0>
  VSS27  = GND
  CA0_A  = M_F_CPU1_SA_CA<0>
  VSS28  = GND
  CA2_A  = M_F_CPU1_SA_CA<2>
  VSS29  = GND
  CA4_A  = M_F_CPU1_SA_CA<4>
  VSS30  = GND
  CA6_A  = M_F_CPU1_SA_CA<6>
  VSS31  = GND
  PAR_A  = M_F_CPU1_SA_PAR
  VSS32  = GND
  CA0_B  = M_F_CPU1_SB_CA<0>
  VSS33  = GND
  CA2_B  = M_F_CPU1_SB_CA<2>
  VSS34  = GND
  CA4_B  = M_F_CPU1_SB_CA<4>
  VSS35  = GND
  CA6_B  = M_F_CPU1_SB_CA<6>
  VSS36  = GND
  CS0_B_N  = M_F_CPU1_SB_CS_N<0>
  VSS37  = GND
  \lbd||rsp_a_n\  = M_F_CPU1_SA_RSP<0>
  \lbs||rsp_b_n\  = M_F_CPU1_SB_RSP<0>
  VSS38  = GND
  CB4_B  = M_F_CPU1_SB_CB<4>
  VSS39  = GND
  CB5_B  = M_F_CPU1_SB_CB<5>
  VSS40  = GND
  \dqs9_b_t||tdqs9_b_t||dbi4_b_n\  = M_F_CPU1_SB_DQS_DP<9>
  \dqs9_b_c||tdqs9_b_c\  = M_F_CPU1_SB_DQS_DN<9>
  VSS41  = GND
  CB0_B  = M_F_CPU1_SB_CB<0>
  VSS42  = GND
  CB1_B  = M_F_CPU1_SB_CB<1>
  VSS43  = GND
  DQ0_B  = M_F_CPU1_SB_DQ<0>
  VSS44  = GND
  DQ1_B  = M_F_CPU1_SB_DQ<1>
  VSS45  = GND
  DQS0_B_T  = M_F_CPU1_SB_DQS_DP<0>
  DQS0_B_C  = M_F_CPU1_SB_DQS_DN<0>
  VSS46  = GND
  DQ4_B  = M_F_CPU1_SB_DQ<4>
  VSS47  = GND
  DQ5_B  = M_F_CPU1_SB_DQ<5>
  VSS48  = GND
  DQ8_B  = M_F_CPU1_SB_DQ<8>
  VSS49  = GND
  DQ9_B  = M_F_CPU1_SB_DQ<9>
  VSS50  = GND
  DQS1_B_T  = M_F_CPU1_SB_DQS_DP<1>
  DQS1_B_C  = M_F_CPU1_SB_DQS_DN<1>
  VSS51  = GND
  DQ12_B  = M_F_CPU1_SB_DQ<12>
  VSS52  = GND
  DQ13_B  = M_F_CPU1_SB_DQ<13>
  VSS53  = GND
  DQ16_B  = M_F_CPU1_SB_DQ<16>
  VSS54  = GND
  DQ17_B  = M_F_CPU1_SB_DQ<17>
  VSS55  = GND
  DQS2_B_T  = M_F_CPU1_SB_DQS_DP<2>
  DQS2_B_C  = M_F_CPU1_SB_DQS_DN<2>
  VSS56  = GND
  DQ20_B  = M_F_CPU1_SB_DQ<20>
  VSS57  = GND
  DQ21_B  = M_F_CPU1_SB_DQ<21>
  VSS58  = GND
  DQ24_B  = M_F_CPU1_SB_DQ<24>
  VSS59  = GND
  DQ25_B  = M_F_CPU1_SB_DQ<25>
  VSS60  = GND
  DQS3_B_T  = M_F_CPU1_SB_DQS_DP<3>
  DQS3_B_C  = M_F_CPU1_SB_DQS_DN<3>
  VSS61  = GND
  DQ28_B  = M_F_CPU1_SB_DQ<28>
  VSS62  = GND
  DQ29_B  = M_F_CPU1_SB_DQ<29>
  VSS63  = GND
  RFU1  = NC
  VIN_BULK1  = P12V_MEM_CPU1
  VIN_BULK2  = P12V_MEM_CPU1
  \pwr_good||fail_n\  = PWRGD_CHF_CPU1_DIMM
  HAS  = PD_CHF_CPU1_DIMM_SAA
  RFU2  = NC
  RFU3  = NC
  VSS64  = GND
  DQ2_A  = M_F_CPU1_SA_DQ<2>
  VSS65  = GND
  DQ3_A  = M_F_CPU1_SA_DQ<3>
  VSS66  = GND
  \dqs5_a_c||tdqs5_a_c||dqs5_a_t||tdqs5_a_t\  = M_F_CPU1_SA_DQS_DN<5>
  \dqs5_a_t||tdqs5_a_t\  = M_F_CPU1_SA_DQS_DP<5>
  VSS67  = GND
  DQ6_A  = M_F_CPU1_SA_DQ<6>
  VSS68  = GND
  DQ7_A  = M_F_CPU1_SA_DQ<7>
  VSS69  = GND
  DQ10_A  = M_F_CPU1_SA_DQ<10>
  VSS70  = GND
  DQ11_A  = M_F_CPU1_SA_DQ<11>
  VSS71  = GND
  \dqs6_a_c||tdqs6_a_c||dqs6_a_t||tdqs6_a_t\  = M_F_CPU1_SA_DQS_DN<6>
  \dqs6_a_t||tdqs6_a_t\  = M_F_CPU1_SA_DQS_DP<6>
  VSS72  = GND
  DQ14_A  = M_F_CPU1_SA_DQ<14>
  VSS73  = GND
  DQ15_A  = M_F_CPU1_SA_DQ<15>
  VSS74  = GND
  DQ18_A  = M_F_CPU1_SA_DQ<18>
  VSS75  = GND
  DQ19_A  = M_F_CPU1_SA_DQ<19>
  VSS76  = GND
  \dqs7_a_c||tdqs7_a_c\  = M_F_CPU1_SA_DQS_DN<7>
  \dqs7_a_t||tdqs7_a_t\  = M_F_CPU1_SA_DQS_DP<7>
  VSS77  = GND
  DQ22_A  = M_F_CPU1_SA_DQ<22>
  VSS78  = GND
  DQ23_A  = M_F_CPU1_SA_DQ<23>
  VSS79  = GND
  DQ26_A  = M_F_CPU1_SA_DQ<26>
  VSS80  = GND
  DQ27_A  = M_F_CPU1_SA_DQ<27>
  VSS81  = GND
  \dqs8_a_c||tdqs8_a_c\  = M_F_CPU1_SA_DQS_DN<8>
  \dqs8_a_t||tdqs8_a_t\  = M_F_CPU1_SA_DQS_DP<8>
  VSS82  = GND
  DQ30_A  = M_F_CPU1_SA_DQ<30>
  VSS83  = GND
  DQ31_A  = M_F_CPU1_SA_DQ<31>
  VSS84  = GND
  CB2_A  = M_F_CPU1_SA_CB<2>
  VSS85  = GND
  CB3_A  = M_F_CPU1_SA_CB<3>
  VSS86  = GND
  \dqs9_a_c||tdqs9_a_c\  = M_F_CPU1_SA_DQS_DN<9>
  \dqs9_a_t||tdqs9_a_t\  = M_F_CPU1_SA_DQS_DP<9>
  VSS87  = GND
  CB6_A  = M_F_CPU1_SA_CB<6>
  VSS88  = GND
  CB7_A  = M_F_CPU1_SA_CB<7>
  VSS89  = GND
  RESET_N  = M_F_CPU1_RESET_N
  VSS90  = GND
  CS1_A_N  = M_F_CPU1_SA_CS_N<1>
  VSS91  = GND
  CA1_A  = M_F_CPU1_SA_CA<1>
  VSS92  = GND
  CA3_A  = M_F_CPU1_SA_CA<3>
  VSS93  = GND
  CA5_A  = M_F_CPU1_SA_CA<5>
  VSS94  = GND
  CK_T  = M_F_CPU1_CLK_DP<0>
  CK_C  = M_F_CPU1_CLK_DN<0>
  VSS95  = GND
  RFU4  = NC
  CA1_B  = M_F_CPU1_SB_CA<1>
  VSS96  = GND
  CA3_B  = M_F_CPU1_SB_CA<3>
  VSS97  = GND
  CA5_B  = M_F_CPU1_SB_CA<5>
  VSS98  = GND
  PAR_B  = M_F_CPU1_SB_PAR
  VSS99  = GND
  CS1_B_N  = M_F_CPU1_SB_CS_N<1>
  VSS100  = GND
  RFU5  = NC
  RFU6  = NC
  VSS101  = GND
  CB6_B  = M_F_CPU1_SB_CB<6>
  VSS102  = GND
  CB7_B  = M_F_CPU1_SB_CB<7>
  VSS103  = GND
  DQS4_B_C  = M_F_CPU1_SB_DQS_DN<4>
  DQS4_B_T  = M_F_CPU1_SB_DQS_DP<4>
  VSS104  = GND
  CB2_B  = M_F_CPU1_SB_CB<2>
  VSS105  = GND
  CB3_B  = M_F_CPU1_SB_CB<3>
  VSS106  = GND
  DQ2_B  = M_F_CPU1_SB_DQ<2>
  VSS107  = GND
  DQ3_B  = M_F_CPU1_SB_DQ<3>
  VSS108  = GND
  \dqs5_b_c||tdqs5_b_c\  = M_F_CPU1_SB_DQS_DN<5>
  \dqs5_b_t||tdqs5_b_t\  = M_F_CPU1_SB_DQS_DP<5>
  VSS109  = GND
  DQ6_B  = M_F_CPU1_SB_DQ<6>
  VSS110  = GND
  DQ7_B  = M_F_CPU1_SB_DQ<7>
  VSS111  = GND
  DQ10_B  = M_F_CPU1_SB_DQ<10>
  VSS112  = GND
  DQ11_B  = M_F_CPU1_SB_DQ<11>
  VSS113  = GND
  \dqs6_b_c||tdqs6_b_c\  = M_F_CPU1_SB_DQS_DN<6>
  \dqs6_b_t||tdqs6_b_t\  = M_F_CPU1_SB_DQS_DP<6>
  VSS114  = GND
  DQ14_B  = M_F_CPU1_SB_DQ<14>
  VSS115  = GND
  DQ15_B  = M_F_CPU1_SB_DQ<15>
  VSS116  = GND
  DQ18_B  = M_F_CPU1_SB_DQ<18>
  VSS117  = GND
  DQ19_B  = M_F_CPU1_SB_DQ<19>
  VSS118  = GND
  \dqs7_b_c||tdqs7_b_c\  = M_F_CPU1_SB_DQS_DN<7>
  \dqs7_b_t||tdqs7_b_t\  = M_F_CPU1_SB_DQS_DP<7>
  VSS119  = GND
  DQ22_B  = M_F_CPU1_SB_DQ<22>
  VSS120  = GND
  DQ23_B  = M_F_CPU1_SB_DQ<23>
  VSS121  = GND
  DQ26_B  = M_F_CPU1_SB_DQ<26>
  VSS122  = GND
  DQ27_B  = M_F_CPU1_SB_DQ<27>
  VSS123  = GND
  \dqs8_b_c||tdqs8_b_c\  = M_F_CPU1_SB_DQS_DN<8>
  \dqs8_b_t||tdqs8_b_t\  = M_F_CPU1_SB_DQS_DP<8>
  VSS124  = GND
  DQ30_B  = M_F_CPU1_SB_DQ<30>
  VSS125  = GND
  DQ31_B  = M_F_CPU1_SB_DQ<31>
  VSS126  = GND
  G1  = GND
  G2  = GND
  G3  = GND

(kicad_pcb
	(version 20260206)
	(generator "pcbnew")
	(generator_version "10.0")
	(general
		(thickness 1.6)
		(legacy_teardrops no)
	)
	(paper "A4")
	(title_block
		(title "04192023_DAF0TMB3IC0_F0TG_MB_C_brd_V02_OCP.brd")
		(comment 1 "Grand Teton / footprint 4248 of 8354 (J33), pads 93-138 of 291")
	)
	(layers
		(0 "F.Cu" signal "TOP")
		(4 "In1.Cu" signal "GND")
		(6 "In2.Cu" signal "IN1")
		(8 "In3.Cu" signal "GND1")
		(10 "In4.Cu" signal "IN2")
		(12 "In5.Cu" signal "GND2")
		(14 "In6.Cu" signal "IN3")
		(16 "In7.Cu" signal "GND3")
		(18 "In8.Cu" signal "VCC")
		(20 "In9.Cu" signal "VCC1")
		(22 "In10.Cu" signal "GND4")
		(24 "In11.Cu" signal "IN4")
		(26 "In12.Cu" signal "GND5")
		(28 "In13.Cu" signal "IN5")
		(30 "In14.Cu" signal "GND6")
		(32 "In15.Cu" signal "IN6")
		(34 "In16.Cu" signal "GND7")
		(2 "B.Cu" signal "BOTTOM")
		(9 "F.Adhes" user "F.Adhesive")
		(11 "B.Adhes" user "B.Adhesive")
		(13 "F.Paste" user "Package Geometry/Pastemask Top")
		(15 "B.Paste" user "Package Geometry/Pastemask Bottom")
		(5 "F.SilkS" user "Ref Des/Silkscreen Top")
		(7 "B.SilkS" user "Ref Des/Silkscreen Bottom")
		(1 "F.Mask" user "Board Geometry/Soldermask Top")
		(3 "B.Mask" user "Board Geometry/Soldermask Bottom")
		(17 "Dwgs.User" user "User.Drawings")
		(19 "Cmts.User" user "User.Comments")
		(21 "Eco1.User" user "User.Eco1")
		(23 "Eco2.User" user "User.Eco2")
		(25 "Edge.Cuts" user "Board Geometry/Outline")
		(27 "Margin" user)
		(31 "F.CrtYd" user "Package Geometry/Place Bound Top")
		(29 "B.CrtYd" user "Package Geometry/Place Bound Bottom")
		(35 "F.Fab" user "Ref Des/Assembly Top")
		(33 "B.Fab" user "Ref Des/Assembly Bottom")
	)
	(footprint ""
		(layer "F.Cu")
		(at 19.658076 -255.560322 180)
		(property "Reference" "J33"
			(at -1.25984 -82.079846 0)
			(unlocked yes)
			(layer "F.SilkS")
			(effects
				(font
					(size 0.7874 0.5842)
					(thickness 0.1524)
				)
			)
		)
		(property "Value" ""
			(at 0 0 180)
			(layer "F.Fab")
			(effects
				(font
					(size 1.27 1.27)
				)
			)
		)
		(duplicate_pad_numbers_are_jumpers no)
		(pad "93" smd rect
			(at -2.050034 19.975068 90)
			(size 0.519938 1.4986)
			(layers "F.Cu" "F.Mask" "F.Paste")
			(net "M_F_CPU1_SB_DQS_DP<9>")
		)
		(pad "94" smd rect
			(at -2.050034 20.824952 90)
			(size 0.519938 1.4986)
			(layers "F.Cu" "F.Mask" "F.Paste")
			(net "M_F_CPU1_SB_DQS_DN<9>")
		)
		(pad "95" smd rect
			(at -2.050034 21.67509 90)
			(size 0.519938 1.4986)
			(layers "F.Cu" "F.Mask" "F.Paste")
			(net "GND")
		)
		(pad "96" smd rect
			(at -2.050034 22.524974 90)
			(size 0.519938 1.4986)
			(layers "F.Cu" "F.Mask" "F.Paste")
			(net "M_F_CPU1_SB_CB<0>")
		)
		(pad "97" smd rect
			(at -2.050034 23.375112 90)
			(size 0.519938 1.4986)
			(layers "F.Cu" "F.Mask" "F.Paste")
			(net "GND")
		)
		(pad "98" smd rect
			(at -2.050034 24.224996 90)
			(size 0.519938 1.4986)
			(layers "F.Cu" "F.Mask" "F.Paste")
			(net "M_F_CPU1_SB_CB<1>")
		)
		(pad "99" smd rect
			(at -2.050034 25.07488 90)
			(size 0.519938 1.4986)
			(layers "F.Cu" "F.Mask" "F.Paste")
			(net "GND")
		)
		(pad "100" smd rect
			(at -2.050034 25.925018 90)
			(size 0.519938 1.4986)
			(layers "F.Cu" "F.Mask" "F.Paste")
			(net "M_F_CPU1_SB_DQ<0>")
		)
		(pad "101" smd rect
			(at -2.050034 26.774902 90)
			(size 0.519938 1.4986)
			(layers "F.Cu" "F.Mask" "F.Paste")
			(net "GND")
		)
		(pad "102" smd rect
			(at -2.050034 27.62504 90)
			(size 0.519938 1.4986)
			(layers "F.Cu" "F.Mask" "F.Paste")
			(net "M_F_CPU1_SB_DQ<1>")
		)
		(pad "103" smd rect
			(at -2.050034 28.474924 90)
			(size 0.519938 1.4986)
			(layers "F.Cu" "F.Mask" "F.Paste")
			(net "GND")
		)
		(pad "104" smd rect
			(at -2.050034 29.325062 90)
			(size 0.519938 1.4986)
			(layers "F.Cu" "F.Mask" "F.Paste")
			(net "M_F_CPU1_SB_DQS_DP<0>")
		)
		(pad "105" smd rect
			(at -2.050034 30.174946 90)
			(size 0.519938 1.4986)
			(layers "F.Cu" "F.Mask" "F.Paste")
			(net "M_F_CPU1_SB_DQS_DN<0>")
		)
		(pad "106" smd rect
			(at -2.050034 31.025084 90)
			(size 0.519938 1.4986)
			(layers "F.Cu" "F.Mask" "F.Paste")
			(net "GND")
		)
		(pad "107" smd rect
			(at -2.050034 31.874968 90)
			(size 0.519938 1.4986)
			(layers "F.Cu" "F.Mask" "F.Paste")
			(net "M_F_CPU1_SB_DQ<4>")
		)
		(pad "108" smd rect
			(at -2.050034 32.725106 90)
			(size 0.519938 1.4986)
			(layers "F.Cu" "F.Mask" "F.Paste")
			(net "GND")
		)
		(pad "109" smd rect
			(at -2.050034 33.57499 90)
			(size 0.519938 1.4986)
			(layers "F.Cu" "F.Mask" "F.Paste")
			(net "M_F_CPU1_SB_DQ<5>")
		)
		(pad "110" smd rect
			(at -2.050034 34.425128 90)
			(size 0.519938 1.4986)
			(layers "F.Cu" "F.Mask" "F.Paste")
			(net "GND")
		)
		(pad "111" smd rect
			(at -2.050034 35.275012 90)
			(size 0.519938 1.4986)
			(layers "F.Cu" "F.Mask" "F.Paste")
			(net "M_F_CPU1_SB_DQ<8>")
		)
		(pad "112" smd rect
			(at -2.050034 36.124896 90)
			(size 0.519938 1.4986)
			(layers "F.Cu" "F.Mask" "F.Paste")
			(net "GND")
		)
		(pad "113" smd rect
			(at -2.050034 36.975034 90)
			(size 0.519938 1.4986)
			(layers "F.Cu" "F.Mask" "F.Paste")
			(net "M_F_CPU1_SB_DQ<9>")
		)
		(pad "114" smd rect
			(at -2.050034 37.824918 90)
			(size 0.519938 1.4986)
			(layers "F.Cu" "F.Mask" "F.Paste")
			(net "GND")
		)
		(pad "115" smd rect
			(at -2.050034 38.675056 90)
			(size 0.519938 1.4986)
			(layers "F.Cu" "F.Mask" "F.Paste")
			(net "M_F_CPU1_SB_DQS_DP<1>")
		)
		(pad "116" smd rect
			(at -2.050034 39.52494 90)
			(size 0.519938 1.4986)
			(layers "F.Cu" "F.Mask" "F.Paste")
			(net "M_F_CPU1_SB_DQS_DN<1>")
		)
		(pad "117" smd rect
			(at -2.050034 40.375078 90)
			(size 0.519938 1.4986)
			(layers "F.Cu" "F.Mask" "F.Paste")
			(net "GND")
		)
		(pad "118" smd rect
			(at -2.050034 41.224962 90)
			(size 0.519938 1.4986)
			(layers "F.Cu" "F.Mask" "F.Paste")
			(net "M_F_CPU1_SB_DQ<12>")
		)
		(pad "119" smd rect
			(at -2.050034 42.0751 90)
			(size 0.519938 1.4986)
			(layers "F.Cu" "F.Mask" "F.Paste")
			(net "GND")
		)
		(pad "120" smd rect
			(at -2.050034 42.924984 90)
			(size 0.519938 1.4986)
			(layers "F.Cu" "F.Mask" "F.Paste")
			(net "M_F_CPU1_SB_DQ<13>")
		)
		(pad "121" smd rect
			(at -2.050034 43.775122 90)
			(size 0.519938 1.4986)
			(layers "F.Cu" "F.Mask" "F.Paste")
			(net "GND")
		)
		(pad "122" smd rect
			(at -2.050034 44.625006 90)
			(size 0.519938 1.4986)
			(layers "F.Cu" "F.Mask" "F.Paste")
			(net "M_F_CPU1_SB_DQ<16>")
		)
		(pad "123" smd rect
			(at -2.050034 45.47489 90)
			(size 0.519938 1.4986)
			(layers "F.Cu" "F.Mask" "F.Paste")
			(net "GND")
		)
		(pad "124" smd rect
			(at -2.050034 46.325028 90)
			(size 0.519938 1.4986)
			(layers "F.Cu" "F.Mask" "F.Paste")
			(net "M_F_CPU1_SB_DQ<17>")
		)
		(pad "125" smd rect
			(at -2.050034 47.174912 90)
			(size 0.519938 1.4986)
			(layers "F.Cu" "F.Mask" "F.Paste")
			(net "GND")
		)
		(pad "126" smd rect
			(at -2.050034 48.02505 90)
			(size 0.519938 1.4986)
			(layers "F.Cu" "F.Mask" "F.Paste")
			(net "M_F_CPU1_SB_DQS_DP<2>")
		)
		(pad "127" smd rect
			(at -2.050034 48.874934 90)
			(size 0.519938 1.4986)
			(layers "F.Cu" "F.Mask" "F.Paste")
			(net "M_F_CPU1_SB_DQS_DN<2>")
		)
		(pad "128" smd rect
			(at -2.050034 49.725072 90)
			(size 0.519938 1.4986)
			(layers "F.Cu" "F.Mask" "F.Paste")
			(net "GND")
		)
		(pad "129" smd rect
			(at -2.050034 50.574956 90)
			(size 0.519938 1.4986)
			(layers "F.Cu" "F.Mask" "F.Paste")
			(net "M_F_CPU1_SB_DQ<20>")
		)
		(pad "130" smd rect
			(at -2.050034 51.425094 90)
			(size 0.519938 1.4986)
			(layers "F.Cu" "F.Mask" "F.Paste")
			(net "GND")
		)
		(pad "131" smd rect
			(at -2.050034 52.274978 90)
			(size 0.519938 1.4986)
			(layers "F.Cu" "F.Mask" "F.Paste")
			(net "M_F_CPU1_SB_DQ<21>")
		)
		(pad "132" smd rect
			(at -2.050034 53.125116 90)
			(size 0.519938 1.4986)
			(layers "F.Cu" "F.Mask" "F.Paste")
			(net "GND")
		)
		(pad "133" smd rect
			(at -2.050034 53.975 90)
			(size 0.519938 1.4986)
			(layers "F.Cu" "F.Mask" "F.Paste")
			(net "M_F_CPU1_SB_DQ<24>")
		)
		(pad "134" smd rect
			(at -2.050034 54.824884 90)
			(size 0.519938 1.4986)
			(layers "F.Cu" "F.Mask" "F.Paste")
			(net "GND")
		)
		(pad "135" smd rect
			(at -2.050034 55.675022 90)
			(size 0.519938 1.4986)
			(layers "F.Cu" "F.Mask" "F.Paste")
			(net "M_F_CPU1_SB_DQ<25>")
		)
		(pad "136" smd rect
			(at -2.050034 56.524906 90)
			(size 0.519938 1.4986)
			(layers "F.Cu" "F.Mask" "F.Paste")
			(net "GND")
		)
		(pad "137" smd rect
			(at -2.050034 57.375044 90)
			(size 0.519938 1.4986)
			(layers "F.Cu" "F.Mask" "F.Paste")
			(net "M_F_CPU1_SB_DQS_DP<3>")
		)
		(pad "138" smd rect
			(at -2.050034 58.224928 90)
			(size 0.519938 1.4986)
			(layers "F.Cu" "F.Mask" "F.Paste")
			(net "M_F_CPU1_SB_DQS_DN<3>")
		)
	)
)
